FILE_TYPE = MACRO_DRAWING;
SET COLOR_WIRE YELLOW;
SET COLOR_PROP MONO;
SET COLOR_DOT WHITE;
SET COLOR_ARC YELLOW;
SET COLOR_BODY GREEN;
SET COLOR_NOTE MONO;
SET PROP_DISPLAY VALUE;
SET PAGE_NUMBER P12;
FORCEADD INTEL_CORP_BPAGE..1
(13000 175);
FORCEPROP 1 LAST CDS_CON_LAST_MODIFIED Fri Jun 16 17:48:01 2017
J 0
(11575 500);
PAINT ORANGE (11575 500);
DISPLAY INVISIBLE (11575 500);
FORCEPROP 1 LAST CUSTOM_TXT_CDS <CURRENT_DESIGN_SHEET> OF <TOTAL_DESIGN_SHEETS>
J 0
(12500 200);
PAINT ORANGE (12500 200);
FORCEPROP 2 LAST CUSTOM_TXT_CDS <XR_PAGE_TITLE>
J 0
(5110 5425);
DISPLAY 0.638298 (5110 5425);
PAINT PINK (5110 5425);
DISPLAY INVISIBLE (5110 5425);
FORCEPROP 2 LAST CUSTOM_TXT_CDS <CON_LAST_MODIFIED>
J 0
(9000 275);
PAINT ORANGE (9000 275);
FORCEPROP 2 LAST CUSTOM_TXT_CDS <CON_PAGE_NUM> OF <CON_TOTAL_PAGES>
J 0
(12500 200);
PAINT GREEN (12500 200);
FORCEPROP 1 LAST SCH_TITLE ADR BLOCK DIAGRAM
J 0
(5050 225);
DISPLAY 1.212766 (5050 225);
PAINT ORANGE (5050 225);
FORCEPROP 2 LAST PAGE_BORDER TRUE
J 0
(5110 5425);
DISPLAY 0.851064 (5110 5425);
PAINT PINK (5110 5425);
DISPLAY INVISIBLE (5110 5425);
FORCEPROP 2 LAST CDS_LIB mstr_symbols
J 0
(13000 175);
PAINT MONO (13000 175);
DISPLAY INVISIBLE (13000 175);
FORCEPROP 1 LAST COMMENT_BODY TRUE
J 0
(13012 187);
DISPLAY 0.446809 (13012 187);
PAINT GREEN (13012 187);
DISPLAY INVISIBLE (13012 187);
FORCEPROP 2 LAST CDS_XR_PAGE_TITLE CR-12 : @BASEBOARD_FAB2_LIB.BASEBOARD_FAB2(SCH_1):PAGE12
J 0
(5110 5425);
DISPLAY 0.638298 (5110 5425);
PAINT PINK (5110 5425);
DISPLAY INVISIBLE (5110 5425);
FORCENOTE
$CDS_IMAGE|ADR_block_diagram_20160411.jpg|7770|5500
(9025 2375) 0;
DISPLAY LEFT (9025 2375);
QUIT
